(kicad_pcb
	(version 20241229)
	(generator "pcbnew")
	(generator_version "9.0")
	(general
		(thickness 1.62)
		(legacy_teardrops no)
	)
	(paper "A4")
	(title_block
		(title "OCuLink to 10GbE adapter")
		(date "2026-02-23")
		(rev "1.1.0")
		(company "Antmicro Ltd")
		(comment 1 "www.antmicro.com")
		(comment 9 "footprints 264-264 of 510")
	)
	(layers
		(0 "F.Cu" signal)
		(4 "In1.Cu" signal)
		(6 "In2.Cu" signal)
		(8 "In3.Cu" signal)
		(10 "In4.Cu" signal)
		(12 "In5.Cu" signal)
		(14 "In6.Cu" signal)
		(2 "B.Cu" signal)
		(9 "F.Adhes" user "F.Adhesive")
		(11 "B.Adhes" user "B.Adhesive")
		(13 "F.Paste" user)
		(15 "B.Paste" user)
		(5 "F.SilkS" user "F.Silkscreen")
		(7 "B.SilkS" user "B.Silkscreen")
		(1 "F.Mask" user)
		(3 "B.Mask" user)
		(17 "Dwgs.User" user "User.Drawings")
		(19 "Cmts.User" user "User.Comments")
		(21 "Eco1.User" user "User.Eco1")
		(23 "Eco2.User" user "User.Eco2")
		(25 "Edge.Cuts" user)
		(27 "Margin" user)
		(31 "F.CrtYd" user "F.Courtyard")
		(29 "B.CrtYd" user "B.Courtyard")
		(35 "F.Fab" user)
		(33 "B.Fab" user)
	)
	(footprint "antmicro-footprints:R_0402_1005Metric"
		(layer "F.Cu")
		(at 53.099998 100.550002 -90)
		(descr "Resistor SMD 0402")
		(tags "resistor SMD 0402")
		(property "Reference" "R16"
			(at -1.090002 2.909998 90)
			(layer "F.SilkS")
			(effects
				(font
					(size 0.7 0.7)
					(thickness 0.15)
				)
				(justify right top)
			)
		)
		(property "Value" "R_0R_0402"
			(at -1.011843 1.772046 90)
			(layer "F.Fab")
			(hide yes)
			(effects
				(font
					(size 0.7 0.7)
					(thickness 0.15)
				)
				(justify right top)
			)
		)
		(property "Datasheet" "https://industrial.panasonic.com/cdbs/www-data/pdf/RDA0000/AOA0000C301.pdf"
			(at 0 0 90)
			(layer "F.Fab")
			(hide yes)
			(effects
				(font
					(size 1.27 1.27)
					(thickness 0.15)
				)
			)
		)
		(property "Description" "SMD Chip Resistor, Jumper, 0 ohm, 100 mW, 0402 [1005 Metric], Thick Film, General Purpose"
			(at 0 0 90)
			(layer "F.Fab")
			(hide yes)
			(effects
				(font
					(size 1.27 1.27)
					(thickness 0.15)
				)
			)
		)
		(property "MPN" "ERJ2GE0R00X"
			(at 0 0 270)
			(unlocked yes)
			(layer "F.Fab")
			(hide yes)
			(effects
				(font
					(size 1 1)
					(thickness 0.15)
				)
			)
		)
		(property "Manufacturer" "Panasonic"
			(at 0 0 270)
			(unlocked yes)
			(layer "F.Fab")
			(hide yes)
			(effects
				(font
					(size 1 1)
					(thickness 0.15)
				)
			)
		)
		(property "License" "Apache-2.0"
			(at 0 0 270)
			(unlocked yes)
			(layer "F.Fab")
			(hide yes)
			(effects
				(font
					(size 1 1)
					(thickness 0.15)
				)
			)
		)
		(property "Author" "Antmicro"
			(at 0 0 270)
			(unlocked yes)
			(layer "F.Fab")
			(hide yes)
			(effects
				(font
					(size 1 1)
					(thickness 0.15)
				)
			)
		)
		(property "Val" "0R"
			(at 0 0 270)
			(unlocked yes)
			(layer "F.Fab")
			(hide yes)
			(effects
				(font
					(size 1 1)
					(thickness 0.15)
				)
			)
		)
		(property "Tolerance" "~"
			(at 0 0 270)
			(unlocked yes)
			(layer "F.Fab")
			(hide yes)
			(effects
				(font
					(size 1 1)
					(thickness 0.15)
				)
			)
		)
		(property "Current" "1A"
			(at 0 0 270)
			(unlocked yes)
			(layer "F.Fab")
			(hide yes)
			(effects
				(font
					(size 1 1)
					(thickness 0.15)
				)
			)
		)
		(sheetname "/Power/")
		(sheetfile "power.kicad_sch")
		(attr smd)
		(fp_rect
			(start -0.925 -0.47)
			(end 0.925 0.47)
			(stroke
				(width 0.05)
				(type default)
			)
			(fill no)
			(layer "F.CrtYd")
		)
		(fp_rect
			(start -0.5 -0.25)
			(end 0.5 0.25)
			(stroke
				(width 0.15)
				(type solid)
			)
			(fill no)
			(layer "F.Fab")
		)
		(pad "1" smd roundrect
			(at -0.48 0 270)
			(size 0.59 0.64)
			(layers "F.Cu" "F.Mask" "F.Paste")
			(roundrect_rratio 0.25)
			(net 342 "/Power/VCCD_PG")
			(pintype "passive")
		)
		(pad "2" smd roundrect
			(at 0.48 0 270)
			(size 0.59 0.64)
			(layers "F.Cu" "F.Mask" "F.Paste")
			(roundrect_rratio 0.25)
			(net 353 "/Power/1V88_EN")
			(pintype "passive")
		)
	)
)
